#ISCELL
  logical_power cad_note *
  *
#ISCELL
  mstr_misc dns *
  *
#ISCELL
  pure_quanta quanta_title_block_c *
  *
#ISCELL
  logical_power universal_gnd *
  page150_i1
#ISCELL
  standard offpage *
  page150_i10
#ISCELL
  standard tap *
  page150_i100
#ISCELL
  standard tap *
  page150_i101
#ISCELL
  standard tap *
  page150_i102
#ISCELL
  standard tap *
  page150_i103
#ISCELL
  standard tap *
  page150_i104
#ISCELL
  standard tap *
  page150_i105
#ISCELL
  standard tap *
  page150_i106
#ISCELL
  standard tap *
  page150_i107
#ISCELL
  standard tap *
  page150_i108
#ISCELL
  standard tap *
  page150_i109
#CELL
  pure_quanta q_cap *
  page150_i110
#CELL
  pure_quanta q_cap *
  page150_i111
#ISCELL
  logical_power universal_gnd *
  page150_i112
#CELL
  pure_quanta q_cap *
  page150_i113
#CELL
  pure_quanta q_cap *
  page150_i114
#CELL
  pure_quanta q_cap *
  page150_i115
#CELL
  pure_quanta q_cap *
  page150_i116
#ISCELL
  standard offpage *
  page150_i117
#CELL
  pure_quanta q_res *
  page150_i118
#CELL
  pure_quanta q_res *
  page150_i119
#ISCELL
  standard offpage *
  page150_i12
#ISCELL
  logical_power universal_power *
  page150_i120
#ISCELL
  standard offpage *
  page150_i121
#ISCELL
  standard offpage *
  page150_i122
#ISCELL
  standard tap *
  page150_i123
#ISCELL
  standard tap *
  page150_i124
#ISCELL
  standard tap *
  page150_i125
#ISCELL
  standard tap *
  page150_i126
#ISCELL
  standard tap *
  page150_i127
#ISCELL
  standard tap *
  page150_i128
#ISCELL
  standard tap *
  page150_i129
#ISCELL
  standard tap *
  page150_i130
#ISCELL
  standard tap *
  page150_i131
#ISCELL
  standard tap *
  page150_i132
#ISCELL
  standard tap *
  page150_i133
#ISCELL
  standard tap *
  page150_i134
#ISCELL
  standard tap *
  page150_i136
#ISCELL
  standard tap *
  page150_i137
#ISCELL
  standard tap *
  page150_i138
#ISCELL
  standard offpage *
  page150_i140
#ISCELL
  standard offpage *
  page150_i142
#ISCELL
  standard offpage *
  page150_i143
#ISCELL
  standard offpage *
  page150_i144
#ISCELL
  standard offpage *
  page150_i145
#ISCELL
  standard offpage *
  page150_i146
#ISCELL
  standard offpage *
  page150_i147
#ISCELL
  logical_power universal_gnd *
  page150_i148
#CELL
  pure_quanta q_res *
  page150_i149
#ISCELL
  standard offpage *
  page150_i15
#ISCELL
  standard offpage *
  page150_i150
#CELL
  pure_quanta q_res *
  page150_i151
#ISCELL
  standard offpage *
  page150_i152
#ISCELL
  standard offpage *
  page150_i153
#ISCELL
  standard offpage *
  page150_i154
#ISCELL
  standard offpage *
  page150_i155
#ISCELL
  standard offpage *
  page150_i156
#ISCELL
  standard offpage *
  page150_i157
#ISCELL
  standard offpage *
  page150_i158
#ISCELL
  standard offpage *
  page150_i159
#ISCELL
  standard offpage *
  page150_i16
#ISCELL
  standard offpage *
  page150_i160
#ISCELL
  standard offpage *
  page150_i161
#ISCELL
  standard offpage *
  page150_i162
#ISCELL
  standard offpage *
  page150_i163
#ISCELL
  standard offpage *
  page150_i164
#ISCELL
  logical_power universal_gnd *
  page150_i167
#CELL
  pure_quanta q_cap *
  page150_i168
#ISCELL
  standard tap *
  page150_i169
#ISCELL
  standard tap *
  page150_i17
#ISCELL
  standard offpage *
  page150_i171
#ISCELL
  logical_power universal_power *
  page150_i173
#ISCELL
  logical_power universal_power *
  page150_i174
#ISCELL
  standard tap *
  page150_i176
#ISCELL
  standard tap *
  page150_i177
#ISCELL
  standard tap *
  page150_i179
#ISCELL
  standard tap *
  page150_i180
#ISCELL
  standard tap *
  page150_i182
#ISCELL
  standard tap *
  page150_i183
#ISCELL
  standard tap *
  page150_i185
#ISCELL
  standard tap *
  page150_i186
#ISCELL
  standard tap *
  page150_i188
#ISCELL
  standard tap *
  page150_i189
#ISCELL
  standard tap *
  page150_i191
#ISCELL
  standard tap *
  page150_i192
#ISCELL
  standard tap *
  page150_i194
#ISCELL
  standard tap *
  page150_i195
#ISCELL
  standard tap *
  page150_i197
#ISCELL
  standard tap *
  page150_i198
#CELL
  pure_quanta sconn168_me1016810202011 *
  page150_i199
#CELL
  pure_quanta q_res *
  page150_i2
#ISCELL
  standard tap *
  page150_i20
#ISCELL
  standard tap *
  page150_i202
#ISCELL
  standard tap *
  page150_i203
#ISCELL
  standard tap *
  page150_i205
#ISCELL
  standard tap *
  page150_i206
#ISCELL
  standard tap *
  page150_i21
#ISCELL
  standard offpage *
  page150_i211
#CELL
  pure_quanta q_res *
  page150_i212
#ISCELL
  standard offpage *
  page150_i213
#CELL
  pure_quanta q_res *
  page150_i215
#CELL
  pure_quanta q_res *
  page150_i217
#CELL
  pure_quanta q_res *
  page150_i218
#ISCELL
  standard offpage *
  page150_i219
#CELL
  pure_quanta q_res *
  page150_i220
#ISCELL
  logical_power universal_gnd *
  page150_i25
#ISCELL
  standard tap *
  page150_i28
#ISCELL
  logical_power universal_gnd *
  page150_i3
#ISCELL
  standard tap *
  page150_i30
#ISCELL
  standard tap *
  page150_i32
#ISCELL
  logical_power universal_gnd *
  page150_i34
#CELL
  pure_quanta q_res *
  page150_i35
#CELL
  pure_quanta q_res *
  page150_i36
#CELL
  pure_quanta q_res *
  page150_i37
#ISCELL
  standard offpage *
  page150_i38
#ISCELL
  standard offpage *
  page150_i39
#CELL
  pure_quanta q_res *
  page150_i4
#ISCELL
  standard offpage *
  page150_i40
#ISCELL
  standard offpage *
  page150_i41
#ISCELL
  standard offpage *
  page150_i42
#ISCELL
  standard offpage *
  page150_i43
#ISCELL
  standard offpage *
  page150_i44
#ISCELL
  standard offpage *
  page150_i45
#ISCELL
  standard offpage *
  page150_i46
#ISCELL
  standard offpage *
  page150_i47
#ISCELL
  standard offpage *
  page150_i48
#CELL
  pure_quanta q_res *
  page150_i5
#ISCELL
  standard offpage *
  page150_i50
#CELL
  pure_quanta q_res *
  page150_i51
#CELL
  pure_quanta q_res *
  page150_i52
#CELL
  pure_quanta q_res *
  page150_i53
#CELL
  pure_quanta q_res *
  page150_i54
#ISCELL
  standard offpage *
  page150_i55
#CELL
  pure_quanta q_res *
  page150_i58
#ISCELL
  standard tap *
  page150_i59
#CELL
  pure_quanta q_res *
  page150_i6
#ISCELL
  standard tap *
  page150_i62
#ISCELL
  standard tap *
  page150_i63
#ISCELL
  standard tap *
  page150_i66
#ISCELL
  standard tap *
  page150_i69
#ISCELL
  logical_power universal_power *
  page150_i7
#ISCELL
  standard tap *
  page150_i70
#ISCELL
  standard tap *
  page150_i73
#ISCELL
  standard offpage *
  page150_i76
#ISCELL
  standard offpage *
  page150_i77
#ISCELL
  standard offpage *
  page150_i78
#ISCELL
  standard offpage *
  page150_i79
#ISCELL
  standard offpage *
  page150_i8
#ISCELL
  standard offpage *
  page150_i80
#ISCELL
  standard offpage *
  page150_i81
#ISCELL
  standard offpage *
  page150_i82
#ISCELL
  standard offpage *
  page150_i83
#ISCELL
  standard offpage *
  page150_i84
#ISCELL
  standard offpage *
  page150_i85
#ISCELL
  logical_power universal_gnd *
  page150_i88
#CELL
  pure_quanta q_cap *
  page150_i89
#ISCELL
  standard offpage *
  page150_i9
#CELL
  pure_quanta q_cap *
  page150_i90
#CELL
  pure_quanta q_cap *
  page150_i91
#ISCELL
  logical_power universal_power *
  page150_i92
#ISCELL
  logical_power universal_power *
  page150_i93
#ISCELL
  logical_power universal_gnd *
  page150_i94
#ISCELL
  standard tap *
  page150_i95
#ISCELL
  standard tap *
  page150_i96
#ISCELL
  standard tap *
  page150_i97
#ISCELL
  standard tap *
  page150_i98
#ISCELL
  standard tap *
  page150_i99
